(kicad_pcb
	(version 20260206)
	(generator "pcbnew")
	(generator_version "10.0")
	(general
		(thickness 1.6)
		(legacy_teardrops no)
	)
	(paper "A4")
	(title_block
		(title "Bryce Canyon_R.DPB_16317-1_OCP.brd")
		(comment 1 "Bryce Canyon / footprints 2099-2099 of 2099")
	)
	(layers
		(0 "F.Cu" signal "TOP")
		(4 "In1.Cu" signal "L2GND")
		(6 "In2.Cu" signal "L3")
		(8 "In3.Cu" signal "L4VCC")
		(10 "In4.Cu" signal "L5VCC")
		(12 "In5.Cu" signal "L6")
		(14 "In6.Cu" signal "L7GND")
		(2 "B.Cu" signal "BOTTOM")
		(9 "F.Adhes" user "F.Adhesive")
		(11 "B.Adhes" user "B.Adhesive")
		(13 "F.Paste" user "Package Geometry/Pastemask Top")
		(15 "B.Paste" user "Package Geometry/Pastemask Bottom")
		(5 "F.SilkS" user "Ref Des/Silkscreen Top")
		(7 "B.SilkS" user "Ref Des/Silkscreen Bottom")
		(1 "F.Mask" user "Board Geometry/Soldermask Top")
		(3 "B.Mask" user "Board Geometry/Soldermask Bottom")
		(17 "Dwgs.User" user "User.Drawings")
		(19 "Cmts.User" user "User.Comments")
		(21 "Eco1.User" user "User.Eco1")
		(23 "Eco2.User" user "User.Eco2")
		(25 "Edge.Cuts" user "Board Geometry/Outline")
		(27 "Margin" user)
		(31 "F.CrtYd" user "Package Geometry/Place Bound Top")
		(29 "B.CrtYd" user "Package Geometry/Place Bound Bottom")
		(35 "F.Fab" user "Ref Des/Assembly Top")
		(33 "B.Fab" user "Ref Des/Assembly Bottom")
	)
	(footprint ""
		(layer "B.Cu")
		(at 432.653186 -115.114578 90)
		(property "Reference" "C681"
			(at 0 0 90)
			(layer "B.SilkS")
			(hide yes)
			(effects
				(font
					(size 1.27 1.27)
				)
				(justify mirror)
			)
		)
		(property "Value" "SC1U16V3KX-5GP"
			(at 0 -2.8194 90)
			(unlocked yes)
			(layer "B.Fab")
			(hide yes)
			(effects
				(font
					(size 1.016 1.016)
					(thickness 0.1524)
				)
				(justify mirror)
			)
		)
		(property "Device Type" "C603H36"
			(at 0 -4.3434 90)
			(unlocked yes)
			(layer "B.Fab")
			(hide yes)
			(effects
				(font
					(size 1.016 1.016)
					(thickness 0.1524)
				)
				(justify mirror)
			)
		)
		(duplicate_pad_numbers_are_jumpers no)
		(fp_line
			(start -0.508 0)
			(end 0.508 0)
			(stroke
				(width 0.2032)
				(type default)
			)
			(layer "B.SilkS")
		)
		(fp_rect
			(start 0.5842 1.3335)
			(end -0.5842 -1.3335)
			(stroke
				(width 0)
				(type default)
			)
			(fill no)
			(layer "B.CrtYd")
		)
		(fp_rect
			(start 0.5842 1.3335)
			(end -0.5842 -1.3335)
			(stroke
				(width 0)
				(type default)
			)
			(fill no)
			(layer "B.Fab")
		)
		(pad "1" smd custom
			(at 0 -0.762 270)
			(size 0.2159 0.2159)
			(layers "B.Cu" "B.Mask" "B.Paste")
			(net "GND")
			(options
				(clearance outline)
				(anchor circle)
			)
			(primitives
				(gr_poly
					(pts
						(arc
							(start -0.3302 0.4318)
							(mid -0.402042 0.402042)
							(end -0.4318 0.3302)
						)
						(arc
							(start -0.4318 -0.3302)
							(mid -0.402042 -0.402042)
							(end -0.3302 -0.4318)
						)
						(arc
							(start 0.3302 -0.4318)
							(mid 0.402042 -0.402042)
							(end 0.4318 -0.3302)
						)
						(arc
							(start 0.4318 0.3302)
							(mid 0.402042 0.402042)
							(end 0.3302 0.4318)
						)
					)
					(width 0)
					(fill yes)
				)
			)
		)
		(pad "2" smd custom
			(at 0 0.762 270)
			(size 0.2159 0.2159)
			(layers "B.Cu" "B.Mask" "B.Paste")
			(net "P5V_B_4_VREG")
			(options
				(clearance outline)
				(anchor circle)
			)
			(primitives
				(gr_poly
					(pts
						(arc
							(start -0.3302 0.4318)
							(mid -0.402042 0.402042)
							(end -0.4318 0.3302)
						)
						(arc
							(start -0.4318 -0.3302)
							(mid -0.402042 -0.402042)
							(end -0.3302 -0.4318)
						)
						(arc
							(start 0.3302 -0.4318)
							(mid 0.402042 -0.402042)
							(end 0.4318 -0.3302)
						)
						(arc
							(start 0.4318 0.3302)
							(mid 0.402042 0.402042)
							(end 0.3302 0.4318)
						)
					)
					(width 0)
					(fill yes)
				)
			)
		)
	)
)
